(kicad_pcb
	(version 20260206)
	(generator "pcbnew")
	(generator_version "10.0")
	(general
		(thickness 1.6)
		(legacy_teardrops no)
	)
	(paper "A4")
	(title_block
		(title "03242023_DA0F0TMBIJ0_F0T_Motherboard_J_brd_V01_OCP.brd")
		(comment 1 "Grand Teton / footprints 3957-3961 of 6105")
	)
	(layers
		(0 "F.Cu" signal "TOP")
		(4 "In1.Cu" signal "GND")
		(6 "In2.Cu" signal "IN1")
		(8 "In3.Cu" signal "GND1")
		(10 "In4.Cu" signal "IN2")
		(12 "In5.Cu" signal "GND2")
		(14 "In6.Cu" signal "IN3")
		(16 "In7.Cu" signal "GND3")
		(18 "In8.Cu" signal "VCC")
		(20 "In9.Cu" signal "VCC1")
		(22 "In10.Cu" signal "GND4")
		(24 "In11.Cu" signal "IN4")
		(26 "In12.Cu" signal "GND5")
		(28 "In13.Cu" signal "IN5")
		(30 "In14.Cu" signal "GND6")
		(32 "In15.Cu" signal "IN6")
		(34 "In16.Cu" signal "GND7")
		(2 "B.Cu" signal "BOTTOM")
		(9 "F.Adhes" user "F.Adhesive")
		(11 "B.Adhes" user "B.Adhesive")
		(13 "F.Paste" user "Package Geometry/Pastemask Top")
		(15 "B.Paste" user "Package Geometry/Pastemask Bottom")
		(5 "F.SilkS" user "Ref Des/Silkscreen Top")
		(7 "B.SilkS" user "Ref Des/Silkscreen Bottom")
		(1 "F.Mask" user "Board Geometry/Soldermask Top")
		(3 "B.Mask" user "Board Geometry/Soldermask Bottom")
		(17 "Dwgs.User" user "User.Drawings")
		(19 "Cmts.User" user "User.Comments")
		(21 "Eco1.User" user "User.Eco1")
		(23 "Eco2.User" user "User.Eco2")
		(25 "Edge.Cuts" user "Board Geometry/Outline")
		(27 "Margin" user)
		(31 "F.CrtYd" user "Package Geometry/Place Bound Top")
		(29 "B.CrtYd" user "Package Geometry/Place Bound Bottom")
		(35 "F.Fab" user "Ref Des/Assembly Top")
		(33 "B.Fab" user "Ref Des/Assembly Bottom")
	)
	(footprint ""
		(layer "F.Cu")
		(at 72.708262 -39.319962)
		(property "Reference" "U263"
			(at 2.341626 -3.780282 0)
			(unlocked yes)
			(layer "F.SilkS")
			(effects
				(font
					(size 0.7874 0.5842)
					(thickness 0.1524)
				)
			)
		)
		(property "Value" ""
			(at 0 0 0)
			(layer "F.Fab")
			(effects
				(font
					(size 1.27 1.27)
				)
			)
		)
		(duplicate_pad_numbers_are_jumpers no)
		(fp_line
			(start -1.500124 -1.500124)
			(end -1.004062 -1.500124)
			(stroke
				(width 0.1524)
				(type default)
			)
			(layer "F.SilkS")
		)
		(fp_line
			(start -1.500124 -1.004062)
			(end -1.500124 -1.500124)
			(stroke
				(width 0.1524)
				(type default)
			)
			(layer "F.SilkS")
		)
		(fp_line
			(start -1.500124 1.500124)
			(end -1.500124 1.004062)
			(stroke
				(width 0.1524)
				(type default)
			)
			(layer "F.SilkS")
		)
		(fp_line
			(start -1.004062 1.500124)
			(end -1.500124 1.500124)
			(stroke
				(width 0.1524)
				(type default)
			)
			(layer "F.SilkS")
		)
		(fp_line
			(start 1.004062 -1.500124)
			(end 1.500124 -1.500124)
			(stroke
				(width 0.1524)
				(type default)
			)
			(layer "F.SilkS")
		)
		(fp_line
			(start 1.500124 -1.500124)
			(end 1.500124 -1.004062)
			(stroke
				(width 0.1524)
				(type default)
			)
			(layer "F.SilkS")
		)
		(fp_line
			(start 1.500124 1.004062)
			(end 1.500124 1.500124)
			(stroke
				(width 0.1524)
				(type default)
			)
			(layer "F.SilkS")
		)
		(fp_line
			(start 1.500124 1.500124)
			(end 1.004062 1.500124)
			(stroke
				(width 0.1524)
				(type default)
			)
			(layer "F.SilkS")
		)
		(fp_poly
			(pts
				(xy -1.50241 -2.181098) (xy -1.894586 -1.396492) (xy -2.286762 -2.181098)
			)
			(stroke
				(width 0)
				(type default)
			)
			(fill yes)
			(layer "F.SilkS")
		)
		(fp_line
			(start -1.500124 -1.500124)
			(end 1.500124 -1.500124)
			(stroke
				(width 0.1)
				(type default)
			)
			(layer "F.Fab")
		)
		(fp_line
			(start -1.500124 1.500124)
			(end -1.500124 -1.500124)
			(stroke
				(width 0.1)
				(type default)
			)
			(layer "F.Fab")
		)
		(fp_line
			(start 1.500124 -1.500124)
			(end 1.500124 1.500124)
			(stroke
				(width 0.1)
				(type default)
			)
			(layer "F.Fab")
		)
		(fp_line
			(start 1.500124 1.500124)
			(end -1.500124 1.500124)
			(stroke
				(width 0.1)
				(type default)
			)
			(layer "F.Fab")
		)
		(fp_poly
			(pts
				(xy -2.847848 -1.258062) (xy -2.847848 -0.242062) (xy -1.831848 -0.750062)
			)
			(stroke
				(width 0)
				(type default)
			)
			(fill yes)
			(layer "F.Fab")
		)
		(pad "1" smd rect
			(at -1.400048 -0.750062 270)
			(size 0.2286 0.6096)
			(layers "F.Cu" "F.Mask" "F.Paste")
			(net "INA230_3_A1")
		)
		(pad "2" smd rect
			(at -1.400048 -0.249936 270)
			(size 0.2286 0.6096)
			(layers "F.Cu" "F.Mask" "F.Paste")
			(net "INA230_3_A0")
		)
		(pad "3" smd rect
			(at -1.400048 0.249936 270)
			(size 0.2286 0.6096)
			(layers "F.Cu" "F.Mask" "F.Paste")
			(net "OCP_V3_2_P3V3_ADC_ALERT_R")
		)
		(pad "4" smd rect
			(at -1.400048 0.750062 270)
			(size 0.2286 0.6096)
			(layers "F.Cu" "F.Mask" "F.Paste")
			(net "SMB_INA230_3_3V3AUX_SDA_R1")
		)
		(pad "5" smd rect
			(at -0.750062 1.400048)
			(size 0.2286 0.6096)
			(layers "F.Cu" "F.Mask" "F.Paste")
			(net "SMB_INA230_3_3V3AUX_SCL_R1")
		)
		(pad "6" smd rect
			(at -0.249936 1.400048)
			(size 0.2286 0.6096)
			(layers "F.Cu" "F.Mask" "F.Paste")
			(net "NC_INA230_3_NC0")
		)
		(pad "7" smd rect
			(at 0.249936 1.400048)
			(size 0.2286 0.6096)
			(layers "F.Cu" "F.Mask" "F.Paste")
			(net "NC_INA230_3_NC1")
		)
		(pad "8" smd rect
			(at 0.750062 1.400048)
			(size 0.2286 0.6096)
			(layers "F.Cu" "F.Mask" "F.Paste")
			(net "NC_INA230_3_NC2")
		)
		(pad "9" smd rect
			(at 1.400048 0.750062 270)
			(size 0.2286 0.6096)
			(layers "F.Cu" "F.Mask" "F.Paste")
			(net "P3V3_AUX")
		)
		(pad "10" smd rect
			(at 1.400048 0.249936 270)
			(size 0.2286 0.6096)
			(layers "F.Cu" "F.Mask" "F.Paste")
			(net "GND")
		)
		(pad "11" smd rect
			(at 1.400048 -0.249936 270)
			(size 0.2286 0.6096)
			(layers "F.Cu" "F.Mask" "F.Paste")
			(net "P3V3_OCP_V3_2_R")
		)
		(pad "12" smd rect
			(at 1.400048 -0.750062 270)
			(size 0.2286 0.6096)
			(layers "F.Cu" "F.Mask" "F.Paste")
			(net "VSENSE_P12V_INA230_3_INN")
		)
		(pad "13" smd rect
			(at 0.750062 -1.400048)
			(size 0.2286 0.6096)
			(layers "F.Cu" "F.Mask" "F.Paste")
			(net "VSENSE_P12V_INA230_3_INP")
		)
		(pad "14" smd rect
			(at 0.249936 -1.400048)
			(size 0.2286 0.6096)
			(layers "F.Cu" "F.Mask" "F.Paste")
			(net "NC_INA230_3_NC3")
		)
		(pad "15" smd rect
			(at -0.249936 -1.400048)
			(size 0.2286 0.6096)
			(layers "F.Cu" "F.Mask" "F.Paste")
			(net "NC_INA230_3_NC4")
		)
		(pad "16" smd rect
			(at -0.750062 -1.400048)
			(size 0.2286 0.6096)
			(layers "F.Cu" "F.Mask" "F.Paste")
			(net "NC_INA230_3_NC5")
		)
		(pad "TH" smd rect
			(at 0 0)
			(size 1.7018 1.7018)
			(layers "F.Cu" "F.Mask" "F.Paste")
			(net "GND")
		)
		(zone
			(layer "F.Cu")
			(hatch none 0.5)
			(connect_pads
				(clearance 0)
			)
			(min_thickness 0.25)
			(keepout
				(tracks not_allowed)
				(vias allowed)
				(pads allowed)
				(copperpour not_allowed)
				(footprints allowed)
			)
			(placement
				(enabled no)
				(sheetname "")
			)
			(fill
				(thermal_gap 0.5)
				(thermal_bridge_width 0.5)
				(island_removal_mode 0)
			)
			(polygon
				(pts
					(xy 71.663814 -39.345362) (xy 71.663814 -40.36441) (xy 73.75271 -40.36441) (xy 73.75271 -38.275514)
					(xy 71.663814 -38.275514) (xy 71.663814 -39.319962) (xy 71.806562 -39.319962) (xy 71.806562 -38.418262)
					(xy 73.609962 -38.418262) (xy 73.609962 -40.221662) (xy 71.806562 -40.221662) (xy 71.806562 -39.345362)
				)
			)
		)
	)
	(footprint ""
		(layer "F.Cu")
		(at 20.485608 -385.866894 90)
		(property "Reference" "R4660"
			(at 0 0 90)
			(layer "F.SilkS")
			(hide yes)
			(effects
				(font
					(size 1.27 1.27)
				)
			)
		)
		(property "Value" ""
			(at 0 0 90)
			(layer "F.Fab")
			(effects
				(font
					(size 1.27 1.27)
				)
			)
		)
		(duplicate_pad_numbers_are_jumpers no)
		(fp_line
			(start -0.015494 -0.4064)
			(end 0.7874 -0.4064)
			(stroke
				(width 0.1524)
				(type default)
			)
			(layer "F.SilkS")
		)
		(fp_line
			(start 0.7874 0.4064)
			(end -0.7874 0.4064)
			(stroke
				(width 0.1524)
				(type default)
			)
			(layer "F.SilkS")
		)
		(fp_line
			(start -0.7874 0.4064)
			(end -0.7874 -0.4064)
			(stroke
				(width 0.1524)
				(type default)
			)
			(layer "F.SilkS")
		)
		(fp_line
			(start -0.12065 -0.305054)
			(end -0.12065 -0.2794)
			(stroke
				(width 0.1)
				(type default)
			)
			(layer "F.Fab")
		)
		(fp_line
			(start -0.67945 -0.305054)
			(end -0.12065 -0.305054)
			(stroke
				(width 0.1)
				(type default)
			)
			(layer "F.Fab")
		)
		(fp_line
			(start 0.67945 -0.3048)
			(end 0.67945 0.3048)
			(stroke
				(width 0.1)
				(type default)
			)
			(layer "F.Fab")
		)
		(fp_line
			(start 0.12065 -0.3048)
			(end 0.67945 -0.3048)
			(stroke
				(width 0.1)
				(type default)
			)
			(layer "F.Fab")
		)
		(fp_line
			(start 0.12065 -0.2794)
			(end 0.12065 -0.3048)
			(stroke
				(width 0.1)
				(type default)
			)
			(layer "F.Fab")
		)
		(fp_line
			(start -0.12065 -0.2794)
			(end 0.12065 -0.2794)
			(stroke
				(width 0.1)
				(type default)
			)
			(layer "F.Fab")
		)
		(fp_line
			(start 0.120396 0.2794)
			(end -0.12065 0.2794)
			(stroke
				(width 0.1)
				(type default)
			)
			(layer "F.Fab")
		)
		(fp_line
			(start -0.12065 0.2794)
			(end -0.12065 0.3048)
			(stroke
				(width 0.1)
				(type default)
			)
			(layer "F.Fab")
		)
		(fp_line
			(start 0.67945 0.3048)
			(end 0.120396 0.3048)
			(stroke
				(width 0.1)
				(type default)
			)
			(layer "F.Fab")
		)
		(fp_line
			(start 0.120396 0.3048)
			(end 0.120396 0.2794)
			(stroke
				(width 0.1)
				(type default)
			)
			(layer "F.Fab")
		)
		(fp_line
			(start -0.12065 0.3048)
			(end -0.67945 0.3048)
			(stroke
				(width 0.1)
				(type default)
			)
			(layer "F.Fab")
		)
		(fp_line
			(start -0.67945 0.3048)
			(end -0.67945 -0.305054)
			(stroke
				(width 0.1)
				(type default)
			)
			(layer "F.Fab")
		)
		(pad "1" smd rect
			(at -0.40005 0 270)
			(size 0.4572 0.508)
			(layers "F.Cu" "F.Mask" "F.Paste")
			(net "P2E_MB_BMC_TX_C_DN<0>")
		)
		(pad "2" smd rect
			(at 0.40005 0 270)
			(size 0.4572 0.508)
			(layers "F.Cu" "F.Mask" "F.Paste")
			(net "P2E_MB_BMC_TX_C_R1_DN<0>")
		)
	)
	(footprint ""
		(layer "F.Cu")
		(at 206.7052 -97.6884 90)
		(property "Reference" "R4782"
			(at 0 0 90)
			(layer "F.SilkS")
			(hide yes)
			(effects
				(font
					(size 1.27 1.27)
				)
			)
		)
		(property "Value" ""
			(at 0 0 90)
			(layer "F.Fab")
			(effects
				(font
					(size 1.27 1.27)
				)
			)
		)
		(duplicate_pad_numbers_are_jumpers no)
		(fp_line
			(start 0.7874 -0.4064)
			(end 0.7874 0.4064)
			(stroke
				(width 0.1524)
				(type default)
			)
			(layer "F.SilkS")
		)
		(fp_line
			(start -0.7874 -0.4064)
			(end 0.7874 -0.4064)
			(stroke
				(width 0.1524)
				(type default)
			)
			(layer "F.SilkS")
		)
		(fp_line
			(start 0.7874 0.4064)
			(end -0.7874 0.4064)
			(stroke
				(width 0.1524)
				(type default)
			)
			(layer "F.SilkS")
		)
		(fp_line
			(start -0.7874 0.4064)
			(end -0.7874 -0.4064)
			(stroke
				(width 0.1524)
				(type default)
			)
			(layer "F.SilkS")
		)
		(fp_line
			(start -0.12065 -0.305054)
			(end -0.12065 -0.2794)
			(stroke
				(width 0.1)
				(type default)
			)
			(layer "F.Fab")
		)
		(fp_line
			(start -0.67945 -0.305054)
			(end -0.12065 -0.305054)
			(stroke
				(width 0.1)
				(type default)
			)
			(layer "F.Fab")
		)
		(fp_line
			(start 0.67945 -0.3048)
			(end 0.67945 0.3048)
			(stroke
				(width 0.1)
				(type default)
			)
			(layer "F.Fab")
		)
		(fp_line
			(start 0.12065 -0.3048)
			(end 0.67945 -0.3048)
			(stroke
				(width 0.1)
				(type default)
			)
			(layer "F.Fab")
		)
		(fp_line
			(start 0.12065 -0.2794)
			(end 0.12065 -0.3048)
			(stroke
				(width 0.1)
				(type default)
			)
			(layer "F.Fab")
		)
		(fp_line
			(start -0.12065 -0.2794)
			(end 0.12065 -0.2794)
			(stroke
				(width 0.1)
				(type default)
			)
			(layer "F.Fab")
		)
		(fp_line
			(start 0.120396 0.2794)
			(end -0.12065 0.2794)
			(stroke
				(width 0.1)
				(type default)
			)
			(layer "F.Fab")
		)
		(fp_line
			(start -0.12065 0.2794)
			(end -0.12065 0.3048)
			(stroke
				(width 0.1)
				(type default)
			)
			(layer "F.Fab")
		)
		(fp_line
			(start 0.67945 0.3048)
			(end 0.120396 0.3048)
			(stroke
				(width 0.1)
				(type default)
			)
			(layer "F.Fab")
		)
		(fp_line
			(start 0.120396 0.3048)
			(end 0.120396 0.2794)
			(stroke
				(width 0.1)
				(type default)
			)
			(layer "F.Fab")
		)
		(fp_line
			(start -0.12065 0.3048)
			(end -0.67945 0.3048)
			(stroke
				(width 0.1)
				(type default)
			)
			(layer "F.Fab")
		)
		(fp_line
			(start -0.67945 0.3048)
			(end -0.67945 -0.305054)
			(stroke
				(width 0.1)
				(type default)
			)
			(layer "F.Fab")
		)
		(pad "1" smd circle
			(at -0.40005 0 90)
			(size 0 0)
			(layers "F.Cu" "F.Mask" "F.Paste")
			(net "FM_UV_ADR_TRIGGER_N_R2")
		)
		(pad "2" smd circle
			(at 0.40005 0 90)
			(size 0 0)
			(layers "F.Cu" "F.Mask" "F.Paste")
			(net "FM_UV_ADR_TRIGGER_N")
		)
	)
	(footprint ""
		(layer "F.Cu")
		(at 93.422978 -336.192368 90)
		(property "Reference" "PC557"
			(at 0 0 90)
			(layer "F.SilkS")
			(hide yes)
			(effects
				(font
					(size 1.27 1.27)
				)
			)
		)
		(property "Value" ""
			(at 0 0 90)
			(layer "F.Fab")
			(effects
				(font
					(size 1.27 1.27)
				)
			)
		)
		(duplicate_pad_numbers_are_jumpers no)
		(fp_line
			(start 0.7874 -0.4064)
			(end 0.7874 0.4064)
			(stroke
				(width 0.1524)
				(type default)
			)
			(layer "F.SilkS")
		)
		(fp_line
			(start -0.7874 -0.4064)
			(end 0.7874 -0.4064)
			(stroke
				(width 0.1524)
				(type default)
			)
			(layer "F.SilkS")
		)
		(fp_line
			(start 0.7874 0.4064)
			(end -0.7874 0.4064)
			(stroke
				(width 0.1524)
				(type default)
			)
			(layer "F.SilkS")
		)
		(fp_line
			(start -0.7874 0.4064)
			(end -0.7874 -0.4064)
			(stroke
				(width 0.1524)
				(type default)
			)
			(layer "F.SilkS")
		)
		(fp_line
			(start -0.12065 -0.305054)
			(end -0.12065 -0.2794)
			(stroke
				(width 0.1)
				(type default)
			)
			(layer "F.Fab")
		)
		(fp_line
			(start -0.67945 -0.305054)
			(end -0.12065 -0.305054)
			(stroke
				(width 0.1)
				(type default)
			)
			(layer "F.Fab")
		)
		(fp_line
			(start 0.67945 -0.3048)
			(end 0.67945 0.3048)
			(stroke
				(width 0.1)
				(type default)
			)
			(layer "F.Fab")
		)
		(fp_line
			(start 0.12065 -0.3048)
			(end 0.67945 -0.3048)
			(stroke
				(width 0.1)
				(type default)
			)
			(layer "F.Fab")
		)
		(fp_line
			(start 0.12065 -0.2794)
			(end 0.12065 -0.3048)
			(stroke
				(width 0.1)
				(type default)
			)
			(layer "F.Fab")
		)
		(fp_line
			(start -0.12065 -0.2794)
			(end 0.12065 -0.2794)
			(stroke
				(width 0.1)
				(type default)
			)
			(layer "F.Fab")
		)
		(fp_line
			(start 0.120396 0.2794)
			(end -0.12065 0.2794)
			(stroke
				(width 0.1)
				(type default)
			)
			(layer "F.Fab")
		)
		(fp_line
			(start -0.12065 0.2794)
			(end -0.12065 0.3048)
			(stroke
				(width 0.1)
				(type default)
			)
			(layer "F.Fab")
		)
		(fp_line
			(start 0.67945 0.3048)
			(end 0.120396 0.3048)
			(stroke
				(width 0.1)
				(type default)
			)
			(layer "F.Fab")
		)
		(fp_line
			(start 0.120396 0.3048)
			(end 0.120396 0.2794)
			(stroke
				(width 0.1)
				(type default)
			)
			(layer "F.Fab")
		)
		(fp_line
			(start -0.12065 0.3048)
			(end -0.67945 0.3048)
			(stroke
				(width 0.1)
				(type default)
			)
			(layer "F.Fab")
		)
		(fp_line
			(start -0.67945 0.3048)
			(end -0.67945 -0.305054)
			(stroke
				(width 0.1)
				(type default)
			)
			(layer "F.Fab")
		)
		(pad "1" smd circle
			(at -0.40005 0 90)
			(size 0 0)
			(layers "F.Cu" "F.Mask" "F.Paste")
			(net "PVCCIN_CPU1_VDD1")
		)
		(pad "2" smd circle
			(at 0.40005 0 90)
			(size 0 0)
			(layers "F.Cu" "F.Mask" "F.Paste")
			(net "GND")
		)
	)
	(footprint ""
		(layer "F.Cu")
		(at 17.864582 -410.802836 -90)
		(property "Reference" "R2848"
			(at 0 0 270)
			(layer "F.SilkS")
			(hide yes)
			(effects
				(font
					(size 1.27 1.27)
				)
			)
		)
		(property "Value" ""
			(at 0 0 270)
			(layer "F.Fab")
			(effects
				(font
					(size 1.27 1.27)
				)
			)
		)
		(duplicate_pad_numbers_are_jumpers no)
		(fp_line
			(start -0.7874 0.4064)
			(end -0.7874 -0.4064)
			(stroke
				(width 0.1524)
				(type default)
			)
			(layer "F.SilkS")
		)
		(fp_line
			(start 0.7874 0.4064)
			(end -0.7874 0.4064)
			(stroke
				(width 0.1524)
				(type default)
			)
			(layer "F.SilkS")
		)
		(fp_line
			(start -0.7874 -0.4064)
			(end 0.7874 -0.4064)
			(stroke
				(width 0.1524)
				(type default)
			)
			(layer "F.SilkS")
		)
		(fp_line
			(start 0.7874 -0.4064)
			(end 0.7874 0.4064)
			(stroke
				(width 0.1524)
				(type default)
			)
			(layer "F.SilkS")
		)
		(fp_line
			(start -0.67945 0.3048)
			(end -0.67945 -0.305054)
			(stroke
				(width 0.1)
				(type default)
			)
			(layer "F.Fab")
		)
		(fp_line
			(start -0.12065 0.3048)
			(end -0.67945 0.3048)
			(stroke
				(width 0.1)
				(type default)
			)
			(layer "F.Fab")
		)
		(fp_line
			(start 0.120396 0.3048)
			(end 0.120396 0.2794)
			(stroke
				(width 0.1)
				(type default)
			)
			(layer "F.Fab")
		)
		(fp_line
			(start 0.67945 0.3048)
			(end 0.120396 0.3048)
			(stroke
				(width 0.1)
				(type default)
			)
			(layer "F.Fab")
		)
		(fp_line
			(start -0.12065 0.2794)
			(end -0.12065 0.3048)
			(stroke
				(width 0.1)
				(type default)
			)
			(layer "F.Fab")
		)
		(fp_line
			(start 0.120396 0.2794)
			(end -0.12065 0.2794)
			(stroke
				(width 0.1)
				(type default)
			)
			(layer "F.Fab")
		)
		(fp_line
			(start -0.12065 -0.2794)
			(end 0.12065 -0.2794)
			(stroke
				(width 0.1)
				(type default)
			)
			(layer "F.Fab")
		)
		(fp_line
			(start 0.12065 -0.2794)
			(end 0.12065 -0.3048)
			(stroke
				(width 0.1)
				(type default)
			)
			(layer "F.Fab")
		)
		(fp_line
			(start 0.12065 -0.3048)
			(end 0.67945 -0.3048)
			(stroke
				(width 0.1)
				(type default)
			)
			(layer "F.Fab")
		)
		(fp_line
			(start 0.67945 -0.3048)
			(end 0.67945 0.3048)
			(stroke
				(width 0.1)
				(type default)
			)
			(layer "F.Fab")
		)
		(fp_line
			(start -0.67945 -0.305054)
			(end -0.12065 -0.305054)
			(stroke
				(width 0.1)
				(type default)
			)
			(layer "F.Fab")
		)
		(fp_line
			(start -0.12065 -0.305054)
			(end -0.12065 -0.2794)
			(stroke
				(width 0.1)
				(type default)
			)
			(layer "F.Fab")
		)
		(pad "1" smd circle
			(at -0.40005 0 270)
			(size 0 0)
			(layers "F.Cu" "F.Mask" "F.Paste")
			(net "RST_SWB_BIC_N")
		)
		(pad "2" smd circle
			(at 0.40005 0 270)
			(size 0 0)
			(layers "F.Cu" "F.Mask" "F.Paste")
			(net "RST_SWB_BIC_R_N")
		)
	)
)
